FILE_TYPE = MULTI_PHYS_TABLE;
PART 'MAX9634'
{========================================================================================}
:PACK_TYPE|MATERIAL  |PART_NUMBER      = EnvComp             |PART_NUMBER   |JEDEC_TYPE         |DESCRIPTION                  | CLASS |COMPONENT_TYPE|  HEIGHT    | LPID   | SPEED_URL | Status |RPL| AML | Bus_Unit | Days ;
{========================================================================================}
'SOT'     | 'IC'     | 'H35789-001'(!) = 'YES;YES;YES;UNK;ok;VLD' | 'H35789-001' | 'SOT23_5A'        | 'IC,LIN,SOT23,MAX9634,PMU'  | 'IC'  | 'SMALLSMT'   | '0.057 IN' | '1716' | 'http://speed.intel.com:8081/speed/module/pdm/item/pdm_item_detail_direct.asp?item_cde=H35789-001&item_rev=01&url_param=unused' | 'Design' | 'NO' | '2' | 'SMO_IC' | '???' 
'SOT'     | 'EMPTY'  | 'H35789-001'(!) = 'YES;YES;YES;UNK;ok;VLD' | 'H35789-001' | 'SOT23_5A'        | 'IC,LIN,SOT23,MAX9634,PMU'  | 'IO'  | 'SMALLSMT'   | '0.057 IN' | '1716' | 'http://speed.intel.com:8081/speed/module/pdm/item/pdm_item_detail_direct.asp?item_cde=H35789-001&item_rev=01&url_param=unused' | 'Design' | 'NO' | '2' | 'SMO_IC' | '???' 
END_PART
END.
